# S9S_MB_2U (Grand Teton) — schematic netlist excerpt (pin names and nets, part order shuffled) for the footprints in the layout excerpt that follows; sources: Cadence DE-HDL packaged netlist, KiCad conversion of 03242023_DA0F0TMBIJ0_F0T_Motherboard_J_brd_V01_OCP.brd

PC2184  Q_CAP  0.068UF 16V 10% X7R  pkg 0402  page 302 : A = HSC_SS ; B = AGND_HSC
PC2185  Q_CAP  0.068UF 16V 10% X7R  pkg 0402  page 302 : A = HSC_SS ; B = AGND_HSC

(kicad_pcb
	(version 20260206)
	(generator "pcbnew")
	(generator_version "10.0")
	(general
		(thickness 1.6)
		(legacy_teardrops no)
	)
	(paper "A4")
	(title_block
		(title "03242023_DA0F0TMBIJ0_F0T_Motherboard_J_brd_V01_OCP.brd")
		(comment 1 "Grand Teton / footprints 3778-3779 of 6105")
	)
	(layers
		(0 "F.Cu" signal "TOP")
		(4 "In1.Cu" signal "GND")
		(6 "In2.Cu" signal "IN1")
		(8 "In3.Cu" signal "GND1")
		(10 "In4.Cu" signal "IN2")
		(12 "In5.Cu" signal "GND2")
		(14 "In6.Cu" signal "IN3")
		(16 "In7.Cu" signal "GND3")
		(18 "In8.Cu" signal "VCC")
		(20 "In9.Cu" signal "VCC1")
		(22 "In10.Cu" signal "GND4")
		(24 "In11.Cu" signal "IN4")
		(26 "In12.Cu" signal "GND5")
		(28 "In13.Cu" signal "IN5")
		(30 "In14.Cu" signal "GND6")
		(32 "In15.Cu" signal "IN6")
		(34 "In16.Cu" signal "GND7")
		(2 "B.Cu" signal "BOTTOM")
		(9 "F.Adhes" user "F.Adhesive")
		(11 "B.Adhes" user "B.Adhesive")
		(13 "F.Paste" user "Package Geometry/Pastemask Top")
		(15 "B.Paste" user "Package Geometry/Pastemask Bottom")
		(5 "F.SilkS" user "Ref Des/Silkscreen Top")
		(7 "B.SilkS" user "Ref Des/Silkscreen Bottom")
		(1 "F.Mask" user "Board Geometry/Soldermask Top")
		(3 "B.Mask" user "Board Geometry/Soldermask Bottom")
		(17 "Dwgs.User" user "User.Drawings")
		(19 "Cmts.User" user "User.Comments")
		(21 "Eco1.User" user "User.Eco1")
		(23 "Eco2.User" user "User.Eco2")
		(25 "Edge.Cuts" user "Board Geometry/Outline")
		(27 "Margin" user)
		(31 "F.CrtYd" user "Package Geometry/Place Bound Top")
		(29 "B.CrtYd" user "Package Geometry/Place Bound Bottom")
		(35 "F.Fab" user "Ref Des/Assembly Top")
		(33 "B.Fab" user "Ref Des/Assembly Bottom")
	)
	(footprint ""
		(layer "F.Cu")
		(at 194.856608 -404.086822 180)
		(property "Reference" "PC2184"
			(at 0 0 180)
			(layer "F.SilkS")
			(hide yes)
			(effects
				(font
					(size 1.27 1.27)
				)
			)
		)
		(property "Value" ""
			(at 0 0 180)
			(layer "F.Fab")
			(effects
				(font
					(size 1.27 1.27)
				)
			)
		)
		(duplicate_pad_numbers_are_jumpers no)
		(fp_line
			(start 0.7874 0.4064)
			(end -0.7874 0.4064)
			(stroke
				(width 0.1524)
				(type default)
			)
			(layer "F.SilkS")
		)
		(fp_line
			(start 0.7874 -0.4064)
			(end 0.7874 0.4064)
			(stroke
				(width 0.1524)
				(type default)
			)
			(layer "F.SilkS")
		)
		(fp_line
			(start -0.7874 0.4064)
			(end -0.7874 -0.4064)
			(stroke
				(width 0.1524)
				(type default)
			)
			(layer "F.SilkS")
		)
		(fp_line
			(start -0.7874 -0.4064)
			(end 0.7874 -0.4064)
			(stroke
				(width 0.1524)
				(type default)
			)
			(layer "F.SilkS")
		)
		(fp_line
			(start 0.67945 0.3048)
			(end 0.120396 0.3048)
			(stroke
				(width 0.1)
				(type default)
			)
			(layer "F.Fab")
		)
		(fp_line
			(start 0.67945 -0.3048)
			(end 0.67945 0.3048)
			(stroke
				(width 0.1)
				(type default)
			)
			(layer "F.Fab")
		)
		(fp_line
			(start 0.12065 -0.2794)
			(end 0.12065 -0.3048)
			(stroke
				(width 0.1)
				(type default)
			)
			(layer "F.Fab")
		)
		(fp_line
			(start 0.12065 -0.3048)
			(end 0.67945 -0.3048)
			(stroke
				(width 0.1)
				(type default)
			)
			(layer "F.Fab")
		)
		(fp_line
			(start 0.120396 0.3048)
			(end 0.120396 0.2794)
			(stroke
				(width 0.1)
				(type default)
			)
			(layer "F.Fab")
		)
		(fp_line
			(start 0.120396 0.2794)
			(end -0.12065 0.2794)
			(stroke
				(width 0.1)
				(type default)
			)
			(layer "F.Fab")
		)
		(fp_line
			(start -0.12065 0.3048)
			(end -0.67945 0.3048)
			(stroke
				(width 0.1)
				(type default)
			)
			(layer "F.Fab")
		)
		(fp_line
			(start -0.12065 0.2794)
			(end -0.12065 0.3048)
			(stroke
				(width 0.1)
				(type default)
			)
			(layer "F.Fab")
		)
		(fp_line
			(start -0.12065 -0.2794)
			(end 0.12065 -0.2794)
			(stroke
				(width 0.1)
				(type default)
			)
			(layer "F.Fab")
		)
		(fp_line
			(start -0.12065 -0.305054)
			(end -0.12065 -0.2794)
			(stroke
				(width 0.1)
				(type default)
			)
			(layer "F.Fab")
		)
		(fp_line
			(start -0.67945 0.3048)
			(end -0.67945 -0.305054)
			(stroke
				(width 0.1)
				(type default)
			)
			(layer "F.Fab")
		)
		(fp_line
			(start -0.67945 -0.305054)
			(end -0.12065 -0.305054)
			(stroke
				(width 0.1)
				(type default)
			)
			(layer "F.Fab")
		)
		(pad "1" smd circle
			(at -0.40005 0 180)
			(size 0 0)
			(layers "F.Cu" "F.Mask" "F.Paste")
			(net "HSC_SS")
		)
		(pad "2" smd circle
			(at 0.40005 0 180)
			(size 0 0)
			(layers "F.Cu" "F.Mask" "F.Paste")
			(net "AGND_HSC")
		)
	)
	(footprint ""
		(layer "F.Cu")
		(at 205.397608 -405.839422 180)
		(property "Reference" "PC2185"
			(at 0 0 180)
			(layer "F.SilkS")
			(hide yes)
			(effects
				(font
					(size 1.27 1.27)
				)
			)
		)
		(property "Value" ""
			(at 0 0 180)
			(layer "F.Fab")
			(effects
				(font
					(size 1.27 1.27)
				)
			)
		)
		(duplicate_pad_numbers_are_jumpers no)
		(fp_line
			(start 0.7874 0.4064)
			(end -0.7874 0.4064)
			(stroke
				(width 0.1524)
				(type default)
			)
			(layer "F.SilkS")
		)
		(fp_line
			(start 0.7874 -0.4064)
			(end 0.7874 0.4064)
			(stroke
				(width 0.1524)
				(type default)
			)
			(layer "F.SilkS")
		)
		(fp_line
			(start -0.7874 0.4064)
			(end -0.7874 -0.4064)
			(stroke
				(width 0.1524)
				(type default)
			)
			(layer "F.SilkS")
		)
		(fp_line
			(start -0.7874 -0.4064)
			(end 0.7874 -0.4064)
			(stroke
				(width 0.1524)
				(type default)
			)
			(layer "F.SilkS")
		)
		(fp_line
			(start 0.67945 0.3048)
			(end 0.120396 0.3048)
			(stroke
				(width 0.1)
				(type default)
			)
			(layer "F.Fab")
		)
		(fp_line
			(start 0.67945 -0.3048)
			(end 0.67945 0.3048)
			(stroke
				(width 0.1)
				(type default)
			)
			(layer "F.Fab")
		)
		(fp_line
			(start 0.12065 -0.2794)
			(end 0.12065 -0.3048)
			(stroke
				(width 0.1)
				(type default)
			)
			(layer "F.Fab")
		)
		(fp_line
			(start 0.12065 -0.3048)
			(end 0.67945 -0.3048)
			(stroke
				(width 0.1)
				(type default)
			)
			(layer "F.Fab")
		)
		(fp_line
			(start 0.120396 0.3048)
			(end 0.120396 0.2794)
			(stroke
				(width 0.1)
				(type default)
			)
			(layer "F.Fab")
		)
		(fp_line
			(start 0.120396 0.2794)
			(end -0.12065 0.2794)
			(stroke
				(width 0.1)
				(type default)
			)
			(layer "F.Fab")
		)
		(fp_line
			(start -0.12065 0.3048)
			(end -0.67945 0.3048)
			(stroke
				(width 0.1)
				(type default)
			)
			(layer "F.Fab")
		)
		(fp_line
			(start -0.12065 0.2794)
			(end -0.12065 0.3048)
			(stroke
				(width 0.1)
				(type default)
			)
			(layer "F.Fab")
		)
		(fp_line
			(start -0.12065 -0.2794)
			(end 0.12065 -0.2794)
			(stroke
				(width 0.1)
				(type default)
			)
			(layer "F.Fab")
		)
		(fp_line
			(start -0.12065 -0.305054)
			(end -0.12065 -0.2794)
			(stroke
				(width 0.1)
				(type default)
			)
			(layer "F.Fab")
		)
		(fp_line
			(start -0.67945 0.3048)
			(end -0.67945 -0.305054)
			(stroke
				(width 0.1)
				(type default)
			)
			(layer "F.Fab")
		)
		(fp_line
			(start -0.67945 -0.305054)
			(end -0.12065 -0.305054)
			(stroke
				(width 0.1)
				(type default)
			)
			(layer "F.Fab")
		)
		(pad "1" smd circle
			(at -0.40005 0 180)
			(size 0 0)
			(layers "F.Cu" "F.Mask" "F.Paste")
			(net "HSC_SS")
		)
		(pad "2" smd circle
			(at 0.40005 0 180)
			(size 0 0)
			(layers "F.Cu" "F.Mask" "F.Paste")
			(net "AGND_HSC")
		)
	)
)
